# T6G (Grand Teton) — schematic parts with pin connectivity, parts 8082–8082 of 8303; source: Cadence DE-HDL packaged netlist (pstxprt.dat, pstxnet.dat, pstchip.dat)

U26  GENOA_SP5  SOCKET6096_13568-001 IO  pkg SOCKET6096_93-4X120-45XA  page 37  (pins 2017-2352 of 6096)
  BK65  MFB_CA5  OUT  = M_F_CPU1_SB_CA<5>
  BK66  VSS_BK66  POWER  = GND
  BK67  MFB_CA6  OUT  = M_F_CPU1_SB_CA<6>
  BK68  VSS_BK68  POWER  = GND
  BK69  MEB_CA5  OUT  = M_E_CPU1_SB_CA<5>
  BK70  MEB_CA6  OUT  = M_E_CPU1_SB_CA<6>
  BK71  VSS_BK71  POWER  = GND
  BK72  MAB_CA5  OUT  = M_A_CPU1_SB_CA<5>
  BK73  VSS_BK73  POWER  = GND
  BK74  MAB_CA6  OUT  = M_A_CPU1_SB_CA<6>
  BL1  VSS_BL1  POWER  = GND
  BL2  MGB1_CS_L0  OUT  = NC
  BL3  MGB_PAR  OUT  = M_G_CPU1_SB_PAR
  BL4  VSS_BL4  POWER  = GND
  BL5  MKB1_CS_L0  OUT  = NC
  BL6  VSS_BL6  POWER  = GND
  BL7  MKB_PAR  OUT  = M_K_CPU1_SB_PAR
  BL8  VSS_BL8  POWER  = GND
  BL9  MLB1_CS_L0  OUT  = NC
  BL10  MLB_PAR  OUT  = M_L_CPU1_SB_PAR
  BL11  VSS_BL11  POWER  = GND
  BL12  MHB1_CS_L0  OUT  = NC
  BL13  VSS_BL13  POWER  = GND
  BL14  MHB_PAR  OUT  = M_H_CPU1_SB_PAR
  BL15  VSS_BL15  POWER  = GND
  BL16  MJB1_CS_L0  OUT  = NC
  BL17  MJB_PAR  OUT  = M_J_CPU1_SB_PAR
  BL18  VSS_BL18  POWER  = GND
  BL19  MIB1_CS_L0  OUT  = NC
  BL20  VSS_BL20  POWER  = GND
  BL21  MIB_PAR  OUT  = M_I_CPU1_SB_PAR
  BL22  VSS_BL22  POWER  = GND
  BL23  VDD_11_S3_BL23  POWER  = PVDD11_S3_P1
  BL24  VSS_BL24  POWER  = GND
  BL25  VDD_11_S3_BL25  POWER  = PVDD11_S3_P1
  BL26  VSS_BL26  POWER  = GND
  BL27  VDD_11_S3_BL27  POWER  = PVDD11_S3_P1
  BL28  VSS_BL28  POWER  = GND
  BL48  VDD_11_S3_BL48  POWER  = PVDD11_S3_P1
  BL49  VSS_BL49  POWER  = GND
  BL50  VDDIO_BL50  POWER  = PVDDIO_P1
  BL51  VSS_BL51  POWER  = GND
  BL52  VDDIO_BL52  POWER  = PVDDIO_P1
  BL53  VSS_BL53  POWER  = GND
  BL54  VDDIO_BL54  POWER  = PVDDIO_P1
  BL55  MCB1_CS_L0  OUT  = NC
  BL56  VSS_BL56  POWER  = GND
  BL57  MCB_PAR  OUT  = M_C_CPU1_SB_PAR
  BL58  VSS_BL58  POWER  = GND
  BL59  MDB1_CS_L0  OUT  = NC
  BL60  MDB_PAR  OUT  = M_D_CPU1_SB_PAR
  BL61  VSS_BL61  POWER  = GND
  BL62  MBB1_CS_L0  OUT  = NC
  BL63  VSS_BL63  POWER  = GND
  BL64  MBB_PAR  OUT  = M_B_CPU1_SB_PAR
  BL65  VSS_BL65  POWER  = GND
  BL66  MFB1_CS_L0  OUT  = NC
  BL67  MFB_PAR  OUT  = M_F_CPU1_SB_PAR
  BL68  VSS_BL68  POWER  = GND
  BL69  MEB1_CS_L0  OUT  = NC
  BL70  VSS_BL70  POWER  = GND
  BL71  MEB_PAR  OUT  = M_E_CPU1_SB_PAR
  BL72  VSS_BL72  POWER  = GND
  BL73  MAB1_CS_L0  OUT  = NC
  BL74  MAB_PAR  OUT  = M_A_CPU1_SB_PAR
  BL75  VSS_BL75  POWER  = GND
  BM2  MGB1_CS_L1  OUT  = NC
  BM3  VSS_BM3  POWER  = GND
  BM4  MGB0_CS_L0  OUT  = M_G_CPU1_SB_CS_N<0>
  BM5  VDDCR_SOC_BM5  POWER  = PVDDCR_SOC_P1
  BM6  MKB1_CS_L1  OUT  = NC
  BM7  MKB0_CS_L0  OUT  = M_K_CPU1_SB_CS_N<0>
  BM8  VSS_BM8  POWER  = GND
  BM9  MLB1_CS_L1  OUT  = NC
  BM10  VSS_BM10  POWER  = GND
  BM11  MLB0_CS_L0  OUT  = M_L_CPU1_SB_CS_N<0>
  BM12  VDD_11_S3_BM12  POWER  = PVDD11_S3_P1
  BM13  MHB1_CS_L1  OUT  = NC
  BM14  MHB0_CS_L0  OUT  = M_H_CPU1_SB_CS_N<0>
  BM15  VSS_BM15  POWER  = GND
  BM16  MJB1_CS_L1  OUT  = NC
  BM17  VSS_BM17  POWER  = GND
  BM18  MJB0_CS_L0  OUT  = M_J_CPU1_SB_CS_N<0>
  BM19  VDD_11_S3_BM19  POWER  = PVDD11_S3_P1
  BM20  MIB1_CS_L1  OUT  = NC
  BM21  MIB0_CS_L0  OUT  = M_I_CPU1_SB_CS_N<0>
  BM22  VDD_11_S3_BM22  POWER  = PVDD11_S3_P1
  BM23  VSS_BM23  POWER  = GND
  BM24  VDD_11_S3_BM24  POWER  = PVDD11_S3_P1
  BM25  VSS_BM25  POWER  = GND
  BM26  VDD_11_S3_BM26  POWER  = PVDD11_S3_P1
  BM27  VSS_BM27  POWER  = GND
  BM28  VDD_11_S3_BM28  POWER  = PVDD11_S3_P1
  BM29  VSS_BM29  POWER  = GND
  BM30  VDD_11_S3_BM30  POWER  = PVDD11_S3_P1
  BM31  VSS_BM31  POWER  = GND
  BM32  VDD_11_S3_BM32  POWER  = PVDD11_S3_P1
  BM33  VSS_BM33  POWER  = GND
  BM34  VDD_11_S3_BM34  POWER  = PVDD11_S3_P1
  BM35  VSS_BM35  POWER  = GND
  BM36  VDD_11_S3_BM36  POWER  = PVDD11_S3_P1
  BM37  VSS_BM37  POWER  = GND
  BM39  VDD_11_S3_BM39  POWER  = PVDD11_S3_P1
  BM40  VSS_BM40  POWER  = GND
  BM41  VDD_11_S3_BM41  POWER  = PVDD11_S3_P1
  BM42  VSS_BM42  POWER  = GND
  BM43  VDD_11_S3_BM43  POWER  = PVDD11_S3_P1
  BM44  VSS_BM44  POWER  = GND
  BM45  VDD_11_S3_BM45  POWER  = PVDD11_S3_P1
  BM46  VSS_BM46  POWER  = GND
  BM47  VDD_11_S3_BM47  POWER  = PVDD11_S3_P1
  BM48  VSS_BM48  POWER  = GND
  BM49  VDD_11_S3_BM49  POWER  = PVDD11_S3_P1
  BM50  VSS_BM50  POWER  = GND
  BM51  VDDIO_BM51  POWER  = PVDDIO_P1
  BM52  VSS_BM52  POWER  = GND
  BM53  VDDIO_BM53  POWER  = PVDDIO_P1
  BM54  VSS_BM54  POWER  = GND
  BM55  MCB0_CS_L0  OUT  = M_C_CPU1_SB_CS_N<0>
  BM56  MCB1_CS_L1  OUT  = NC
  BM57  VDDIO_BM57  POWER  = PVDDIO_P1
  BM58  MDB0_CS_L0  OUT  = M_D_CPU1_SB_CS_N<0>
  BM59  VSS_BM59  POWER  = GND
  BM60  MDB1_CS_L1  OUT  = NC
  BM61  VSS_BM61  POWER  = GND
  BM62  MBB0_CS_L0  OUT  = M_B_CPU1_SB_CS_N<0>
  BM63  MBB1_CS_L1  OUT  = NC
  BM64  VDDIO_BM64  POWER  = PVDDIO_P1
  BM65  MFB0_CS_L0  OUT  = M_F_CPU1_SB_CS_N<0>
  BM66  VSS_BM66  POWER  = GND
  BM67  MFB1_CS_L1  OUT  = NC
  BM68  VSS_BM68  POWER  = GND
  BM69  MEB0_CS_L0  OUT  = M_E_CPU1_SB_CS_N<0>
  BM70  MEB1_CS_L1  OUT  = NC
  BM71  VDDIO_BM71  POWER  = PVDDIO_P1
  BM72  MAB0_CS_L0  OUT  = M_A_CPU1_SB_CS_N<0>
  BM73  VSS_BM73  POWER  = GND
  BM74  MAB1_CS_L1  OUT  = NC
  BN1  VSS_BN1  POWER  = GND
  BN2  MGB0_CS_L1  OUT  = M_G_CPU1_SB_CS_N<1>
  BN3  MGA0_RSP_L  IN  = M_G_CPU1_SA_RSP<0>
  BN4  VSS_BN4  POWER  = GND
  BN5  MKB0_CS_L1  OUT  = M_K_CPU1_SB_CS_N<1>
  BN6  VSS_BN6  POWER  = GND
  BN7  MKA0_RSP_L  IN  = M_K_CPU1_SA_RSP<0>
  BN8  VSS_BN8  POWER  = GND
  BN9  MLB0_CS_L1  OUT  = M_L_CPU1_SB_CS_N<1>
  BN10  MLA0_RSP_L  IN  = M_L_CPU1_SA_RSP<0>
  BN11  VSS_BN11  POWER  = GND
  BN12  MHB0_CS_L1  OUT  = M_H_CPU1_SB_CS_N<1>
  BN13  VSS_BN13  POWER  = GND
  BN14  MHA0_RSP_L  IN  = M_H_CPU1_SA_RSP<0>
  BN15  VSS_BN15  POWER  = GND
  BN16  MJB0_CS_L1  OUT  = M_J_CPU1_SB_CS_N<1>
  BN17  MJA0_RSP_L  IN  = M_J_CPU1_SA_RSP<0>
  BN18  VSS_BN18  POWER  = GND
  BN19  MIB0_CS_L1  OUT  = M_I_CPU1_SB_CS_N<1>
  BN20  VSS_BN20  POWER  = GND
  BN21  MIA0_RSP_L  IN  = M_I_CPU1_SA_RSP<0>
  BN22  VSS_BN22  POWER  = GND
  BN23  VDDBT_RTC_G  POWER  = CPU1_VDDBT_RTC_G
  BN24  VSS_BN24  POWER  = GND
  BN25  VDD_11_S3_BN25  POWER  = PVDD11_S3_P1
  BN26  VSS_BN26  POWER  = GND
  BN27  VDDCR_CPU1_BN27  POWER  = PVDDCR_CPU1_P1
  BN28  VSS_BN28  POWER  = GND
  BN29  VDD_11_S3_BN29  POWER  = PVDD11_S3_P1
  BN30  VSS_BN30  POWER  = GND
  BN31  VDDCR_CPU1_BN31  POWER  = PVDDCR_CPU1_P1
  BN32  VSS_BN32  POWER  = GND
  BN33  VDD_11_S3_BN33  POWER  = PVDD11_S3_P1
  BN34  VSS_BN34  POWER  = GND
  BN35  VDDCR_CPU1_BN35  POWER  = PVDDCR_CPU1_P1
  BN36  VSS_BN36  POWER  = GND
  BN40  VDD_11_S3_BN40  POWER  = PVDD11_S3_P1
  BN41  VSS_BN41  POWER  = GND
  BN42  VDDCR_CPU1_BN42  POWER  = PVDDCR_CPU1_P1
  BN43  VSS_BN43  POWER  = GND
  BN44  VDD_11_S3_BN44  POWER  = PVDD11_S3_P1
  BN45  VSS_BN45  POWER  = GND
  BN46  VDDCR_CPU1_BN46  POWER  = PVDDCR_CPU1_P1
  BN47  VSS_BN47  POWER  = GND
  BN48  VDD_11_S3_BN48  POWER  = PVDD11_S3_P1
  BN49  VSS_BN49  POWER  = GND
  BN50  VDDCR_CPU1_BN50  POWER  = PVDDCR_CPU1_P1
  BN51  VSS_BN51  POWER  = GND
  BN52  VDD_33_S5_BN52  POWER  = PVDD_33_S5
  BN53  VSS_BN53  POWER  = GND
  BN54  VDDIO_BN54  POWER  = PVDDIO_P1
  BN55  MCA0_RSP_L  IN  = M_C_CPU1_SA_RSP<0>
  BN56  VSS_BN56  POWER  = GND
  BN57  MCB0_CS_L1  OUT  = M_C_CPU1_SB_CS_N<1>
  BN58  VSS_BN58  POWER  = GND
  BN59  MDA0_RSP_L  IN  = M_D_CPU1_SA_RSP<0>
  BN60  MDB0_CS_L1  OUT  = M_D_CPU1_SB_CS_N<1>
  BN61  VSS_BN61  POWER  = GND
  BN62  MBA0_RSP_L  IN  = M_B_CPU1_SA_RSP<0>
  BN63  VSS_BN63  POWER  = GND
  BN64  MBB0_CS_L1  OUT  = M_B_CPU1_SB_CS_N<1>
  BN65  VSS_BN65  POWER  = GND
  BN66  MFA0_RSP_L  IN  = M_F_CPU1_SA_RSP<0>
  BN67  MFB0_CS_L1  OUT  = M_F_CPU1_SB_CS_N<1>
  BN68  VSS_BN68  POWER  = GND
  BN69  MEA0_RSP_L  IN  = M_E_CPU1_SA_RSP<0>
  BN70  VSS_BN70  POWER  = GND
  BN71  MEB0_CS_L1  OUT  = M_E_CPU1_SB_CS_N<1>
  BN72  VSS_BN72  POWER  = GND
  BN73  MAA0_RSP_L  IN  = M_A_CPU1_SA_RSP<0>
  BN74  MAB0_CS_L1  OUT  = M_A_CPU1_SB_CS_N<1>
  BN75  VSS_BN75  POWER  = GND
  BP2  MGB0_RSP_L  IN  = M_G_CPU1_SB_RSP<0>
  BP3  VSS_BP3  POWER  = GND
  BP4  MGA1_RSP_L  IN  = NC
  BP5  VSS_BP5  POWER  = GND
  BP6  MKB0_RSP_L  IN  = M_K_CPU1_SB_RSP<0>
  BP7  MKA1_RSP_L  IN  = NC
  BP8  VSS_BP8  POWER  = GND
  BP9  MLB0_RSP_L  IN  = M_L_CPU1_SB_RSP<0>
  BP10  VSS_BP10  POWER  = GND
  BP11  MLA1_RSP_L  IN  = NC
  BP12  VSS_BP12  POWER  = GND
  BP13  MHB0_RSP_L  IN  = M_H_CPU1_SB_RSP<0>
  BP14  MHA1_RSP_L  IN  = NC
  BP15  VSS_BP15  POWER  = GND
  BP16  MJB0_RSP_L  IN  = M_J_CPU1_SB_RSP<0>
  BP17  VSS_BP17  POWER  = GND
  BP18  MJA1_RSP_L  IN  = NC
  BP19  VSS_BP19  POWER  = GND
  BP20  MIB0_RSP_L  IN  = M_I_CPU1_SB_RSP<0>
  BP21  MIA1_RSP_L  IN  = NC
  BP22  VDD_11_S3_BP22  POWER  = PVDD11_S3_P1
  BP23  VSS_BP23  POWER  = GND
  BP24  VDDCR_CPU1_BP24  POWER  = PVDDCR_CPU1_P1
  BP25  VSS_BP25  POWER  = GND
  BP26  VDDCR_CPU1_BP26  POWER  = PVDDCR_CPU1_P1
  BP27  VSS_BP27  POWER  = GND
  BP28  VDDCR_CPU1_BP28  POWER  = PVDDCR_CPU1_P1
  BP29  VSS_BP29  POWER  = GND
  BP30  VDDCR_CPU1_BP30  POWER  = PVDDCR_CPU1_P1
  BP31  VSS_BP31  POWER  = GND
  BP32  VDDCR_CPU1_BP32  POWER  = PVDDCR_CPU1_P1
  BP33  VSS_BP33  POWER  = GND
  BP34  VDDCR_CPU1_BP34  POWER  = PVDDCR_CPU1_P1
  BP35  VSS_BP35  POWER  = GND
  BP36  VDDCR_CPU1_BP36  POWER  = PVDDCR_CPU1_P1
  BP37  VSS_BP37  POWER  = GND
  BP39  VDDCR_CPU1_BP39  POWER  = PVDDCR_CPU1_P1
  BP40  VSS_BP40  POWER  = GND
  BP41  VDDCR_CPU1_BP41  POWER  = PVDDCR_CPU1_P1
  BP42  VSS_BP42  POWER  = GND
  BP43  VDDCR_CPU1_BP43  POWER  = PVDDCR_CPU1_P1
  BP44  VSS_BP44  POWER  = GND
  BP45  VDDCR_CPU1_BP45  POWER  = PVDDCR_CPU1_P1
  BP46  VSS_BP46  POWER  = GND
  BP47  VDDCR_CPU1_BP47  POWER  = PVDDCR_CPU1_P1
  BP48  VSS_BP48  POWER  = GND
  BP49  VDDCR_CPU1_BP49  POWER  = PVDDCR_CPU1_P1
  BP50  VSS_BP50  POWER  = GND
  BP51  VDD_33_S5_BP51  POWER  = PVDD_33_S5
  BP52  VSS_BP52  POWER  = GND
  BP53  VDD_33_S5_SENSE  POWER  = TP_VSENSE_PVDD33_S5_P1
  BP54  VSS_BP54  POWER  = GND
  BP55  MCA1_RSP_L  IN  = NC
  BP56  MCB0_RSP_L  IN  = M_C_CPU1_SB_RSP<0>
  BP57  VSS_BP57  POWER  = GND
  BP58  MDA1_RSP_L  IN  = NC
  BP59  VSS_BP59  POWER  = GND
  BP60  MDB0_RSP_L  IN  = M_D_CPU1_SB_RSP<0>
  BP61  VSS_BP61  POWER  = GND
  BP62  MBA1_RSP_L  IN  = NC
  BP63  MBB0_RSP_L  IN  = M_B_CPU1_SB_RSP<0>
  BP64  VSS_BP64  POWER  = GND
  BP65  MFA1_RSP_L  IN  = NC
  BP66  VSS_BP66  POWER  = GND
  BP67  MFB0_RSP_L  IN  = M_F_CPU1_SB_RSP<0>
  BP68  VSS_BP68  POWER  = GND
  BP69  MEA1_RSP_L  IN  = NC
  BP70  MEB0_RSP_L  IN  = M_E_CPU1_SB_RSP<0>
  BP71  VSS_BP71  POWER  = GND
  BP72  MAA1_RSP_L  IN  = NC
  BP73  VSS_BP73  POWER  = GND
  BP74  MAB0_RSP_L  IN  = M_A_CPU1_SB_RSP<0>
  BR1  VSS_BR1  POWER  = GND
  BR2  MGB1_RSP_L  IN  = NC
  BR3  VSS_BR3  POWER  = GND
  BR4  VDD_11_S3_BR4  POWER  = PVDD11_S3_P1
  BR5  MKB1_RSP_L  IN  = NC
  BR6  VSS_BR6  POWER  = GND
  BR7  VSS_BR7  POWER  = GND
  BR8  VSS_BR8  POWER  = GND
  BR9  MLB1_RSP_L  IN  = NC
  BR10  VSS_BR10  POWER  = GND
  BR11  VDD_11_S3_BR11  POWER  = PVDD11_S3_P1
  BR12  MHB1_RSP_L  IN  = NC
  BR13  VSS_BR13  POWER  = GND
  BR14  VSS_BR14  POWER  = GND
  BR15  VSS_BR15  POWER  = GND
  BR16  MJB1_RSP_L  IN  = NC
  BR17  VSS_BR17  POWER  = GND
  BR18  VDD_11_S3_BR18  POWER  = PVDD11_S3_P1
  BR19  MIB1_RSP_L  IN  = NC
  BR20  VSS_BR20  POWER  = GND
  BR21  VSS_BR21  POWER  = GND
  BR22  VSS_BR22  POWER  = GND
  BR23  VDDCR_CPU1_BR23  POWER  = PVDDCR_CPU1_P1
  BR24  VSS_BR24  POWER  = GND
  BR25  VDDCR_CPU1_BR25  POWER  = PVDDCR_CPU1_P1
  BR26  VSS_BR26  POWER  = GND
  BR27  VDDCR_CPU1_BR27  POWER  = PVDDCR_CPU1_P1
  BR28  VSS_BR28  POWER  = GND
  BR29  VDDCR_CPU1_BR29  POWER  = PVDDCR_CPU1_P1
  BR30  VSS_BR30  POWER  = GND
  BR31  VDDCR_CPU1_BR31  POWER  = PVDDCR_CPU1_P1
  BR32  VSS_BR32  POWER  = GND
  BR33  VDDCR_CPU1_BR33  POWER  = PVDDCR_CPU1_P1
  BR34  VSS_BR34  POWER  = GND
  BR35  VDDCR_CPU1_BR35  POWER  = PVDDCR_CPU1_P1
  BR36  VSS_BR36  POWER  = GND
  BR40  VDDCR_CPU1_BR40  POWER  = PVDDCR_CPU1_P1
  BR41  VSS_BR41  POWER  = GND
  BR42  VDDCR_CPU1_BR42  POWER  = PVDDCR_CPU1_P1
  BR43  VSS_BR43  POWER  = GND
  BR44  VDDCR_CPU1_BR44  POWER  = PVDDCR_CPU1_P1
  BR45  VSS_BR45  POWER  = GND
  BR46  VDDCR_CPU1_BR46  POWER  = PVDDCR_CPU1_P1
  BR47  VSS_BR47  POWER  = GND
  BR48  VDDCR_CPU1_BR48  POWER  = PVDDCR_CPU1_P1
  BR49  VSS_BR49  POWER  = GND
  BR50  VDDCR_CPU1_BR50  POWER  = PVDDCR_CPU1_P1
  BR51  VSS_BR51  POWER  = GND
  BR52  VDDCR_CPU1_BR52  POWER  = PVDDCR_CPU1_P1
  BR53  VDDIO_SENSE  POWER  = VSENSE_PVDDIO_P1_DP
  BR54  VSS_SENSE_B  POWER  = VSENSE_VSS_SENSE_B_P1
  BR55  VSS_BR55  POWER  = GND
  BR56  VSS_BR56  POWER  = GND
  BR57  MCB1_RSP_L  IN  = NC
